FILE_TYPE = CONNECTIVITY;
{Allegro Design Entry HDL 16.6-p007 (v16-6-112F) 10/10/2012}
"PAGE_NUMBER" = 58;
0"NC";
1"M_H_DQS_DP<17:0>";
2"M_H_DQS_DN<17:0>";
3"M_H_MA<17:0>";
4"M_H_BA<1:0>";
5"M_H_BG<1:0>";
6"M_H_CKE<3:0>";
7"M_H_CS_N<7:0>";
8"M_H_ODT<3:0>";
9"M_H_DQ<63:0>";
10"M_H_CLK_DN<3:0>";
11"M_H_CLK_DP<3:0>";
12"M_H_ECC<7:0>";
13"M_H_C<2>";
14"M_H_ECC<0>";
15"M_H_ECC<1>";
16"M_H_ECC<2>";
17"M_H_ECC<3>";
18"M_H_ECC<4>";
19"M_H_ECC<5>";
20"M_H_ECC<6>";
21"M_H_ECC<7>";
22"M_H_DQ<0>";
23"M_H_DQ<1>";
24"M_H_DQ<2>";
25"M_H_DQ<3>";
26"M_H_DQ<4>";
27"M_H_DQ<5>";
28"M_H_DQ<6>";
29"M_H_DQ<7>";
30"M_H_DQ<8>";
31"M_H_DQ<9>";
32"M_H_DQ<10>";
33"M_H_CLK_DP<0>";
34"M_H_CLK_DP<1>";
35"M_H_CLK_DP<2>";
36"M_H_CLK_DP<3>";
37"M_H_CLK_DN<0>";
38"M_H_CLK_DN<1>";
39"M_H_CLK_DN<2>";
40"M_H_CLK_DN<3>";
41"M_H_DQ<11>";
42"M_H_DQ<12>";
43"M_H_DQ<13>";
44"M_H_DQ<14>";
45"M_H_DQ<15>";
46"M_H_DQ<16>";
47"M_H_DQ<17>";
48"M_H_DQ<18>";
49"M_H_DQ<19>";
50"M_H_DQ<20>";
51"M_H_DQ<21>";
52"M_H_DQ<22>";
53"M_H_DQ<23>";
54"M_H_DQ<24>";
55"M_H_DQ<25>";
56"M_H_DQ<26>";
57"M_H_DQ<27>";
58"M_H_DQ<28>";
59"M_H_DQ<29>";
60"M_H_DQ<30>";
61"M_H_DQ<31>";
62"M_H_DQ<32>";
63"M_H_DQ<33>";
64"M_H_DQ<34>";
65"M_H_DQ<35>";
66"M_H_DQ<36>";
67"M_H_DQ<37>";
68"M_H_DQ<38>";
69"M_H_DQ<39>";
70"M_H_DQ<40>";
71"M_H_DQ<41>";
72"M_H_DQ<42>";
73"M_H_DQ<43>";
74"M_H_DQ<44>";
75"M_H_DQ<45>";
76"M_H_DQ<46>";
77"M_H_DQ<47>";
78"M_H_DQ<48>";
79"M_H_DQ<49>";
80"M_H_DQ<50>";
81"M_H_DQ<51>";
82"M_H_DQ<52>";
83"M_H_DQ<53>";
84"M_H_DQ<54>";
85"M_H_DQ<55>";
86"M_H_DQ<56>";
87"M_H_DQ<57>";
88"M_H_DQ<58>";
89"M_H_DQ<59>";
90"M_H_DQ<60>";
91"M_H_DQ<61>";
92"M_H_DQ<62>";
93"M_H_DQ<63>";
94"M_H_ODT<0>";
95"M_H_ODT<1>";
96"M_H_ODT<2>";
97"M_H_ODT<3>";
98"M_H_MA<0>";
99"M_H_MA<1>";
100"M_H_MA<2>";
101"M_H_CS_N<0>";
102"M_H_CS_N<1>";
103"M_H_CS_N<2>";
104"M_H_CS_N<3>";
105"M_H_CS_N<4>";
106"M_H_CS_N<5>";
107"M_H_CS_N<6>";
108"M_H_CS_N<7>";
109"M_H_CKE<0>";
110"M_H_CKE<1>";
111"M_H_CKE<2>";
112"M_H_CKE<3>";
113"M_H_BG<0>";
114"M_H_BG<1>";
115"M_H_BA<0>";
116"M_H_BA<1>";
117"M_H_PAR";
118"M_H_ALERT_N";
119"M_H_ACT_N";
120"M_H_MA<3>";
121"M_H_MA<4>";
122"M_H_MA<5>";
123"M_H_MA<6>";
124"M_H_MA<7>";
125"M_H_MA<8>";
126"M_H_MA<9>";
127"M_H_MA<10>";
128"M_H_MA<11>";
129"M_H_MA<12>";
130"M_H_MA<13>";
131"M_H_MA<14>";
132"M_H_MA<15>";
133"M_H_MA<16>";
134"M_H_MA<17>";
135"M_H_DQS_DP<0>";
136"M_H_DQS_DP<1>";
137"M_H_DQS_DP<2>";
138"M_H_DQS_DP<3>";
139"M_H_DQS_DP<4>";
140"M_H_DQS_DP<5>";
141"M_H_DQS_DN<0>";
142"M_H_DQS_DN<1>";
143"M_H_DQS_DN<2>";
144"M_H_DQS_DN<3>";
145"M_H_DQS_DN<4>";
146"M_H_DQS_DN<5>";
147"M_H_DQS_DN<6>";
148"M_H_DQS_DN<7>";
149"M_H_DQS_DN<8>";
150"M_H_DQS_DN<9>";
151"M_H_DQS_DN<10>";
152"M_H_DQS_DN<11>";
153"M_H_DQS_DN<12>";
154"M_H_DQS_DN<13>";
155"M_H_DQS_DN<14>";
156"M_H_DQS_DN<15>";
157"M_H_DQS_DN<16>";
158"M_H_DQS_DN<17>";
159"M_H_DQS_DP<6>";
160"M_H_DQS_DP<7>";
161"M_H_DQS_DP<8>";
162"M_H_DQS_DP<9>";
163"M_H_DQS_DP<10>";
164"M_H_DQS_DP<11>";
165"M_H_DQS_DP<12>";
166"M_H_DQS_DP<13>";
167"M_H_DQS_DP<14>";
168"M_H_DQS_DP<15>";
169"M_H_DQS_DP<16>";
170"M_H_DQS_DP<17>";
%"TAP"
"6","(-5600,825)","0","mstr_standard","I10";
;
HDL_TAP"TRUE"
BODY_TYPE"PLUMBING"
CDS_LIB"mstr_standard";
"B \NAC \NWC"11;
"S \NAC"
BN"0"33;
%"TAP"
"6","(-2875,1575)","2","mstr_standard","I100";
;
HDL_TAP"TRUE"
BODY_TYPE"PLUMBING"
CDS_LIB"mstr_standard";
"B \NAC \NWC"8;
"S \NAC"
BN"3"97;
%"TAP"
"6","(-2875,1525)","2","mstr_standard","I101";
;
HDL_TAP"TRUE"
BODY_TYPE"PLUMBING"
CDS_LIB"mstr_standard";
"B \NAC \NWC"8;
"S \NAC"
BN"2"96;
%"TAP"
"6","(-2875,1475)","2","mstr_standard","I102";
;
HDL_TAP"TRUE"
BODY_TYPE"PLUMBING"
CDS_LIB"mstr_standard";
"B \NAC \NWC"8;
"S \NAC"
BN"1"95;
%"TAP"
"6","(-2875,1675)","2","mstr_standard","I103";
;
HDL_TAP"TRUE"
BODY_TYPE"PLUMBING"
CDS_LIB"mstr_standard";
"B \NAC \NWC"6;
"S \NAC"
BN"0"109;
%"TAP"
"6","(-2875,1725)","2","mstr_standard","I104";
;
HDL_TAP"TRUE"
BODY_TYPE"PLUMBING"
CDS_LIB"mstr_standard";
"B \NAC \NWC"6;
"S \NAC"
BN"1"110;
%"TAP"
"6","(-2875,1775)","2","mstr_standard","I105";
;
HDL_TAP"TRUE"
BODY_TYPE"PLUMBING"
CDS_LIB"mstr_standard";
"B \NAC \NWC"6;
"S \NAC"
BN"2"111;
%"TAP"
"6","(-2875,1825)","2","mstr_standard","I106";
;
HDL_TAP"TRUE"
BODY_TYPE"PLUMBING"
CDS_LIB"mstr_standard";
"B \NAC \NWC"6;
"S \NAC"
BN"3"112;
%"TAP"
"6","(-2875,1925)","2","mstr_standard","I107";
;
HDL_TAP"TRUE"
BODY_TYPE"PLUMBING"
CDS_LIB"mstr_standard";
"B \NAC \NWC"3;
"S \NAC"
BN"0"98;
%"TAP"
"6","(-2875,1975)","2","mstr_standard","I108";
;
HDL_TAP"TRUE"
BODY_TYPE"PLUMBING"
CDS_LIB"mstr_standard";
"B \NAC \NWC"3;
"S \NAC"
BN"1"99;
%"TAP"
"6","(-2875,2075)","2","mstr_standard","I109";
;
HDL_TAP"TRUE"
BODY_TYPE"PLUMBING"
CDS_LIB"mstr_standard";
"B \NAC \NWC"3;
"S \NAC"
BN"3"120;
%"TAP"
"6","(-5600,925)","0","mstr_standard","I11";
;
HDL_TAP"TRUE"
BODY_TYPE"PLUMBING"
CDS_LIB"mstr_standard";
"B \NAC \NWC"11;
"S \NAC"
BN"2"35;
%"TAP"
"6","(-2875,2025)","2","mstr_standard","I110";
;
HDL_TAP"TRUE"
BODY_TYPE"PLUMBING"
CDS_LIB"mstr_standard";
"B \NAC \NWC"3;
"S \NAC"
BN"2"100;
%"TAP"
"6","(-2875,2125)","2","mstr_standard","I111";
;
HDL_TAP"TRUE"
BODY_TYPE"PLUMBING"
CDS_LIB"mstr_standard";
"B \NAC \NWC"3;
"S \NAC"
BN"4"121;
%"TAP"
"6","(-2875,2175)","2","mstr_standard","I112";
;
HDL_TAP"TRUE"
BODY_TYPE"PLUMBING"
CDS_LIB"mstr_standard";
"B \NAC \NWC"3;
"S \NAC"
BN"5"122;
%"TAP"
"6","(-2875,2225)","2","mstr_standard","I113";
;
HDL_TAP"TRUE"
BODY_TYPE"PLUMBING"
CDS_LIB"mstr_standard";
"B \NAC \NWC"3;
"S \NAC"
BN"6"123;
%"TAP"
"6","(-2875,2325)","2","mstr_standard","I114";
;
HDL_TAP"TRUE"
BODY_TYPE"PLUMBING"
CDS_LIB"mstr_standard";
"B \NAC \NWC"3;
"S \NAC"
BN"8"125;
%"TAP"
"6","(-2875,2275)","2","mstr_standard","I115";
;
HDL_TAP"TRUE"
BODY_TYPE"PLUMBING"
CDS_LIB"mstr_standard";
"B \NAC \NWC"3;
"S \NAC"
BN"7"124;
%"TAP"
"6","(-2875,2475)","2","mstr_standard","I116";
;
HDL_TAP"TRUE"
BODY_TYPE"PLUMBING"
CDS_LIB"mstr_standard";
"B \NAC \NWC"3;
"S \NAC"
BN"11"128;
%"TAP"
"6","(-2875,2425)","2","mstr_standard","I117";
;
HDL_TAP"TRUE"
BODY_TYPE"PLUMBING"
CDS_LIB"mstr_standard";
"B \NAC \NWC"3;
"S \NAC"
BN"10"127;
%"TAP"
"6","(-2875,2375)","2","mstr_standard","I118";
;
HDL_TAP"TRUE"
BODY_TYPE"PLUMBING"
CDS_LIB"mstr_standard";
"B \NAC \NWC"3;
"S \NAC"
BN"9"126;
%"TAP"
"6","(-2875,2525)","2","mstr_standard","I119";
;
HDL_TAP"TRUE"
BODY_TYPE"PLUMBING"
CDS_LIB"mstr_standard";
"B \NAC \NWC"3;
"S \NAC"
BN"12"129;
%"TAP"
"6","(-5600,975)","0","mstr_standard","I12";
;
HDL_TAP"TRUE"
BODY_TYPE"PLUMBING"
CDS_LIB"mstr_standard";
"B \NAC \NWC"11;
"S \NAC"
BN"3"36;
%"TAP"
"6","(-2875,2575)","2","mstr_standard","I120";
;
HDL_TAP"TRUE"
BODY_TYPE"PLUMBING"
CDS_LIB"mstr_standard";
"B \NAC \NWC"3;
"S \NAC"
BN"13"130;
%"TAP"
"6","(-2875,2625)","2","mstr_standard","I121";
;
HDL_TAP"TRUE"
BODY_TYPE"PLUMBING"
CDS_LIB"mstr_standard";
"B \NAC \NWC"3;
"S \NAC"
BN"14"131;
%"TAP"
"6","(-2875,2675)","2","mstr_standard","I122";
;
HDL_TAP"TRUE"
BODY_TYPE"PLUMBING"
CDS_LIB"mstr_standard";
"B \NAC \NWC"3;
"S \NAC"
BN"15"132;
%"TAP"
"6","(-2875,2725)","2","mstr_standard","I123";
;
HDL_TAP"TRUE"
BODY_TYPE"PLUMBING"
CDS_LIB"mstr_standard";
"B \NAC \NWC"3;
"S \NAC"
BN"16"133;
%"TAP"
"6","(-2875,2775)","2","mstr_standard","I124";
;
HDL_TAP"TRUE"
BODY_TYPE"PLUMBING"
CDS_LIB"mstr_standard";
"B \NAC \NWC"3;
"S \NAC"
BN"17"134;
%"TAP"
"6","(-2875,2925)","2","mstr_standard","I125";
;
HDL_TAP"TRUE"
BODY_TYPE"PLUMBING"
CDS_LIB"mstr_standard";
"B \NAC \NWC"2;
"S \NAC"
BN"1"142;
%"TAP"
"6","(-2875,2975)","2","mstr_standard","I126";
;
HDL_TAP"TRUE"
BODY_TYPE"PLUMBING"
CDS_LIB"mstr_standard";
"B \NAC \NWC"2;
"S \NAC"
BN"2"143;
%"TAP"
"6","(-2875,2875)","2","mstr_standard","I127";
;
HDL_TAP"TRUE"
BODY_TYPE"PLUMBING"
CDS_LIB"mstr_standard";
"B \NAC \NWC"2;
"S \NAC"
BN"0"141;
%"TAP"
"6","(-2875,3075)","2","mstr_standard","I128";
;
HDL_TAP"TRUE"
BODY_TYPE"PLUMBING"
CDS_LIB"mstr_standard";
"B \NAC \NWC"2;
"S \NAC"
BN"4"145;
%"TAP"
"6","(-2875,3025)","2","mstr_standard","I129";
;
HDL_TAP"TRUE"
BODY_TYPE"PLUMBING"
CDS_LIB"mstr_standard";
"B \NAC \NWC"2;
"S \NAC"
BN"3"144;
%"TAP"
"6","(-5600,1075)","0","mstr_standard","I13";
;
HDL_TAP"TRUE"
BODY_TYPE"PLUMBING"
CDS_LIB"mstr_standard";
"B \NAC \NWC"12;
"S \NAC"
BN"0"14;
%"TAP"
"6","(-2875,3125)","2","mstr_standard","I130";
;
HDL_TAP"TRUE"
BODY_TYPE"PLUMBING"
CDS_LIB"mstr_standard";
"B \NAC \NWC"2;
"S \NAC"
BN"5"146;
%"TAP"
"6","(-2875,3175)","2","mstr_standard","I131";
;
HDL_TAP"TRUE"
BODY_TYPE"PLUMBING"
CDS_LIB"mstr_standard";
"B \NAC \NWC"2;
"S \NAC"
BN"6"147;
%"TAP"
"6","(-2875,3225)","2","mstr_standard","I132";
;
HDL_TAP"TRUE"
BODY_TYPE"PLUMBING"
CDS_LIB"mstr_standard";
"B \NAC \NWC"2;
"S \NAC"
BN"7"148;
%"TAP"
"6","(-2875,3275)","2","mstr_standard","I133";
;
HDL_TAP"TRUE"
BODY_TYPE"PLUMBING"
CDS_LIB"mstr_standard";
"B \NAC \NWC"2;
"S \NAC"
BN"8"149;
%"TAP"
"6","(-2875,3325)","2","mstr_standard","I134";
;
HDL_TAP"TRUE"
BODY_TYPE"PLUMBING"
CDS_LIB"mstr_standard";
"B \NAC \NWC"2;
"S \NAC"
BN"9"150;
%"TAP"
"6","(-2875,3375)","2","mstr_standard","I135";
;
HDL_TAP"TRUE"
BODY_TYPE"PLUMBING"
CDS_LIB"mstr_standard";
"B \NAC \NWC"2;
"S \NAC"
BN"10"151;
%"TAP"
"6","(-2875,3475)","2","mstr_standard","I136";
;
HDL_TAP"TRUE"
BODY_TYPE"PLUMBING"
CDS_LIB"mstr_standard";
"B \NAC \NWC"2;
"S \NAC"
BN"12"153;
%"TAP"
"6","(-2875,3425)","2","mstr_standard","I137";
;
HDL_TAP"TRUE"
BODY_TYPE"PLUMBING"
CDS_LIB"mstr_standard";
"B \NAC \NWC"2;
"S \NAC"
BN"11"152;
%"TAP"
"6","(-2875,3625)","2","mstr_standard","I138";
;
HDL_TAP"TRUE"
BODY_TYPE"PLUMBING"
CDS_LIB"mstr_standard";
"B \NAC \NWC"2;
"S \NAC"
BN"15"156;
%"TAP"
"6","(-2875,3575)","2","mstr_standard","I139";
;
HDL_TAP"TRUE"
BODY_TYPE"PLUMBING"
CDS_LIB"mstr_standard";
"B \NAC \NWC"2;
"S \NAC"
BN"14"155;
%"TAP"
"6","(-5600,1125)","0","mstr_standard","I14";
;
HDL_TAP"TRUE"
BODY_TYPE"PLUMBING"
CDS_LIB"mstr_standard";
"B \NAC \NWC"12;
"S \NAC"
BN"1"15;
%"TAP"
"6","(-2875,3525)","2","mstr_standard","I140";
;
HDL_TAP"TRUE"
BODY_TYPE"PLUMBING"
CDS_LIB"mstr_standard";
"B \NAC \NWC"2;
"S \NAC"
BN"13"154;
%"TAP"
"6","(-2875,3675)","2","mstr_standard","I141";
;
HDL_TAP"TRUE"
BODY_TYPE"PLUMBING"
CDS_LIB"mstr_standard";
"B \NAC \NWC"2;
"S \NAC"
BN"16"157;
%"TAP"
"6","(-2875,3725)","2","mstr_standard","I142";
;
HDL_TAP"TRUE"
BODY_TYPE"PLUMBING"
CDS_LIB"mstr_standard";
"B \NAC \NWC"2;
"S \NAC"
BN"17"158;
%"TAP"
"6","(-2875,3825)","2","mstr_standard","I143";
;
HDL_TAP"TRUE"
BODY_TYPE"PLUMBING"
CDS_LIB"mstr_standard";
"B \NAC \NWC"1;
"S \NAC"
BN"0"135;
%"TAP"
"6","(-2875,3875)","2","mstr_standard","I144";
;
HDL_TAP"TRUE"
BODY_TYPE"PLUMBING"
CDS_LIB"mstr_standard";
"B \NAC \NWC"1;
"S \NAC"
BN"1"136;
%"TAP"
"6","(-2875,3925)","2","mstr_standard","I145";
;
HDL_TAP"TRUE"
BODY_TYPE"PLUMBING"
CDS_LIB"mstr_standard";
"B \NAC \NWC"1;
"S \NAC"
BN"2"137;
%"TAP"
"6","(-2875,3975)","2","mstr_standard","I146";
;
HDL_TAP"TRUE"
BODY_TYPE"PLUMBING"
CDS_LIB"mstr_standard";
"B \NAC \NWC"1;
"S \NAC"
BN"3"138;
%"TAP"
"6","(-5600,1175)","0","mstr_standard","I15";
;
HDL_TAP"TRUE"
BODY_TYPE"PLUMBING"
CDS_LIB"mstr_standard";
"B \NAC \NWC"12;
"S \NAC"
BN"2"16;
%"TAP"
"6","(-2875,4025)","2","mstr_standard","I157";
;
HDL_TAP"TRUE"
BODY_TYPE"PLUMBING"
CDS_LIB"mstr_standard";
"B \NAC \NWC"1;
"S \NAC"
BN"4"139;
%"TAP"
"6","(-2875,4125)","2","mstr_standard","I158";
;
HDL_TAP"TRUE"
BODY_TYPE"PLUMBING"
CDS_LIB"mstr_standard";
"B \NAC \NWC"1;
"S \NAC"
BN"6"159;
%"TAP"
"6","(-2875,4075)","2","mstr_standard","I159";
;
HDL_TAP"TRUE"
BODY_TYPE"PLUMBING"
CDS_LIB"mstr_standard";
"B \NAC \NWC"1;
"S \NAC"
BN"5"140;
%"TAP"
"6","(-5600,1275)","0","mstr_standard","I16";
;
HDL_TAP"TRUE"
BODY_TYPE"PLUMBING"
CDS_LIB"mstr_standard";
"B \NAC \NWC"12;
"S \NAC"
BN"4"18;
%"TAP"
"6","(-2875,4175)","2","mstr_standard","I160";
;
HDL_TAP"TRUE"
BODY_TYPE"PLUMBING"
CDS_LIB"mstr_standard";
"B \NAC \NWC"1;
"S \NAC"
BN"7"160;
%"TAP"
"6","(-2875,4225)","2","mstr_standard","I161";
;
HDL_TAP"TRUE"
BODY_TYPE"PLUMBING"
CDS_LIB"mstr_standard";
"B \NAC \NWC"1;
"S \NAC"
BN"8"161;
%"TAP"
"6","(-2875,4275)","2","mstr_standard","I162";
;
HDL_TAP"TRUE"
BODY_TYPE"PLUMBING"
CDS_LIB"mstr_standard";
"B \NAC \NWC"1;
"S \NAC"
BN"9"162;
%"TAP"
"6","(-2875,4325)","2","mstr_standard","I163";
;
HDL_TAP"TRUE"
BODY_TYPE"PLUMBING"
CDS_LIB"mstr_standard";
"B \NAC \NWC"1;
"S \NAC"
BN"10"163;
%"TAP"
"6","(-2875,4375)","2","mstr_standard","I164";
;
HDL_TAP"TRUE"
BODY_TYPE"PLUMBING"
CDS_LIB"mstr_standard";
"B \NAC \NWC"1;
"S \NAC"
BN"11"164;
%"TAP"
"6","(-2875,4525)","2","mstr_standard","I165";
;
HDL_TAP"TRUE"
BODY_TYPE"PLUMBING"
CDS_LIB"mstr_standard";
"B \NAC \NWC"1;
"S \NAC"
BN"14"167;
%"TAP"
"6","(-2875,4475)","2","mstr_standard","I166";
;
HDL_TAP"TRUE"
BODY_TYPE"PLUMBING"
CDS_LIB"mstr_standard";
"B \NAC \NWC"1;
"S \NAC"
BN"13"166;
%"TAP"
"6","(-2875,4425)","2","mstr_standard","I167";
;
HDL_TAP"TRUE"
BODY_TYPE"PLUMBING"
CDS_LIB"mstr_standard";
"B \NAC \NWC"1;
"S \NAC"
BN"12"165;
%"TAP"
"6","(-2875,4575)","2","mstr_standard","I168";
;
HDL_TAP"TRUE"
BODY_TYPE"PLUMBING"
CDS_LIB"mstr_standard";
"B \NAC \NWC"1;
"S \NAC"
BN"15"168;
%"TAP"
"6","(-2875,4625)","2","mstr_standard","I169";
;
HDL_TAP"TRUE"
BODY_TYPE"PLUMBING"
CDS_LIB"mstr_standard";
"B \NAC \NWC"1;
"S \NAC"
BN"16"169;
%"TAP"
"6","(-5600,1225)","0","mstr_standard","I17";
;
HDL_TAP"TRUE"
BODY_TYPE"PLUMBING"
CDS_LIB"mstr_standard";
"B \NAC \NWC"12;
"S \NAC"
BN"3"17;
%"TAP"
"6","(-2875,4675)","2","mstr_standard","I170";
;
HDL_TAP"TRUE"
BODY_TYPE"PLUMBING"
CDS_LIB"mstr_standard";
"B \NAC \NWC"1;
"S \NAC"
BN"17"170;
%"SKX_EXT_B"
"4","(-4200,2575)","0","chpset_lib","I172";
;
CDS_SEC"4"
CDS_LOCATION"U2D1"
SEC"4"
CDS_LIB"chpset_lib"
SEC_TYPE"BGA1"
PACK_TYPE"BGA1"
MATERIAL"IC"
PART_NUMBER"TBD"
LOCATION"U2D1";
"DDR1_PAR"
$PN"K53"117;
"DDR1_ODT<0>"
$PN"N50"94;
"DDR1_ODT<1>"
$PN"R48"95;
"DDR1_ODT<2>"
$PN"M49"96;
"DDR1_ODT<3>"
$PN"T47"97;
"DDR1_MA<0>"
$PN"J52"98;
"DDR1_MA<1>"
$PN"J58"99;
"DDR1_MA<2>"
$PN"K57"100;
"DDR1_MA<3>"
$PN"N58"120;
"DDR1_MA<4>"
$PN"M59"121;
"DDR1_MA<5>"
$PN"R58"122;
"DDR1_MA<6>"
$PN"T59"123;
"DDR1_MA<7>"
$PN"V61"124;
"DDR1_MA<8>"
$PN"W60"125;
"DDR1_MA<9>"
$PN"K59"126;
"DDR1_MA<10>"
$PN"M55"127;
"DDR1_MA<11>"
$PN"R60"128;
"DDR1_MA<12>"
$PN"T61"129;
"DDR1_MA<13>"
$PN"M51"130;
"DDR1_MA<14>"
$PN"T51"131;
"DDR1_MA<15>"
$PN"N52"132;
"DDR1_MA<16>"
$PN"R52"133;
"DDR1_MA<17>"
$PN"N48"134;
"DDR1_ECC<0>"
$PN"J70"14;
"DDR1_ECC<1>"
$PN"H69"15;
"DDR1_ECC<2>"
$PN"J66"16;
"DDR1_ECC<3>"
$PN"L66"17;
"DDR1_ECC<4>"
$PN"L70"18;
"DDR1_ECC<5>"
$PN"M69"19;
"DDR1_ECC<6>"
$PN"H67"20;
"DDR1_ECC<7>"
$PN"M67"21;
"DDR1_DQS_DP<0>"
$PN"AR80"135;
"DDR1_DQS_DP<1>"
$PN"AE80"136;
"DDR1_DQS_DP<2>"
$PN"H79"137;
"DDR1_DQS_DP<3>"
$PN"F73"138;
"DDR1_DQS_DP<4>"
$PN"R42"139;
"DDR1_DQS_DP<5>"
$PN"E34"140;
"DDR1_DQS_DP<6>"
$PN"E28"159;
"DDR1_DQS_DP<7>"
$PN"Y27"160;
"DDR1_DQS_DP<8>"
$PN"L68"161;
"DDR1_DQS_DP<9>"
$PN"AT81"162;
"DDR1_DQS_DP<10>"
$PN"AF81"163;
"DDR1_DQS_DP<11>"
$PN"F79"164;
"DDR1_DQS_DP<12>"
$PN"D73"165;
"DDR1_DQS_DP<13>"
$PN"L42"166;
"DDR1_DQS_DP<14>"
$PN"C34"167;
"DDR1_DQS_DP<15>"
$PN"C28"168;
"DDR1_DQS_DP<16>"
$PN"V27"169;
"DDR1_DQS_DP<17>"
$PN"J68"170;
"DDR1_DQS_DN<0>"
$PN"AP79"141;
"DDR1_DQS_DN<1>"
$PN"AD79"142;
"DDR1_DQS_DN<2>"
$PN"K79"143;
"DDR1_DQS_DN<3>"
$PN"H73"144;
"DDR1_DQS_DN<4>"
$PN"N42"145;
"DDR1_DQS_DN<5>"
$PN"G34"146;
"DDR1_DQS_DN<6>"
$PN"G28"147;
"DDR1_DQS_DN<7>"
$PN"AB27"148;
"DDR1_DQS_DN<8>"
$PN"N68"149;
"DDR1_DQS_DN<9>"
$PN"AU82"150;
"DDR1_DQS_DN<10>"
$PN"AG82"151;
"DDR1_DQS_DN<11>"
$PN"D79"152;
"DDR1_DQS_DN<12>"
$PN"B73"153;
"DDR1_DQS_DN<13>"
$PN"J42"154;
"DDR1_DQS_DN<14>"
$PN"A34"155;
"DDR1_DQS_DN<15>"
$PN"A28"156;
"DDR1_DQS_DN<16>"
$PN"T27"157;
"DDR1_DQS_DN<17>"
$PN"G68"158;
"DDR1_DQ<0>"
$PN"AV81"22;
"DDR1_DQ<1>"
$PN"AT79"23;
"DDR1_DQ<2>"
$PN"AN82"24;
"DDR1_DQ<3>"
$PN"AM81"25;
"DDR1_DQ<4>"
$PN"AW80"26;
"DDR1_DQ<5>"
$PN"AV79"27;
"DDR1_DQ<6>"
$PN"AR82"28;
"DDR1_DQ<7>"
$PN"AN80"29;
"DDR1_DQ<8>"
$PN"AH81"30;
"DDR1_DQ<9>"
$PN"AF79"31;
"DDR1_DQ<10>"
$PN"AC82"32;
"DDR1_DQ<11>"
$PN"AB81"41;
"DDR1_DQ<12>"
$PN"AJ80"42;
"DDR1_DQ<13>"
$PN"AH79"43;
"DDR1_DQ<14>"
$PN"AE82"44;
"DDR1_DQ<15>"
$PN"AC80"45;
"DDR1_DQ<16>"
$PN"E80"46;
"DDR1_DQ<17>"
$PN"J80"47;
"DDR1_DQ<18>"
$PN"F77"48;
"DDR1_DQ<19>"
$PN"H77"49;
"DDR1_DQ<20>"
$PN"F81"50;
"DDR1_DQ<21>"
$PN"H81"51;
"DDR1_DQ<22>"
$PN"E78"52;
"DDR1_DQ<23>"
$PN"J78"53;
"DDR1_DQ<24>"
$PN"D75"54;
"DDR1_DQ<25>"
$PN"C74"55;
"DDR1_DQ<26>"
$PN"D71"56;
"DDR1_DQ<27>"
$PN"F71"57;
"DDR1_DQ<28>"
$PN"F75"58;
"DDR1_DQ<29>"
$PN"G74"59;
"DDR1_DQ<30>"
$PN"C72"60;
"DDR1_DQ<31>"
$PN"G72"61;
"DDR1_DQ<32>"
$PN"K43"62;
"DDR1_DQ<33>"
$PN"H43"63;
"DDR1_DQ<34>"
$PN"L40"64;
"DDR1_DQ<35>"
$PN"N40"65;
"DDR1_DQ<36>"
$PN"P43"66;
"DDR1_DQ<37>"
$PN"T43"67;
"DDR1_DQ<38>"
$PN"K41"68;
"DDR1_DQ<39>"
$PN"P41"69;
"DDR1_DQ<40>"
$PN"C36"70;
"DDR1_DQ<41>"
$PN"B35"71;
"DDR1_DQ<42>"
$PN"C32"72;
"DDR1_DQ<43>"
$PN"E32"73;
"DDR1_DQ<44>"
$PN"E36"74;
"DDR1_DQ<45>"
$PN"F35"75;
"DDR1_DQ<46>"
$PN"B33"76;
"DDR1_DQ<47>"
$PN"F33"77;
"DDR1_DQ<48>"
$PN"C30"78;
"DDR1_DQ<49>"
$PN"B29"79;
"DDR1_DQ<50>"
$PN"C26"80;
"DDR1_DQ<51>"
$PN"E26"81;
"DDR1_DQ<52>"
$PN"E30"82;
"DDR1_DQ<53>"
$PN"F29"83;
"DDR1_DQ<54>"
$PN"B27"84;
"DDR1_DQ<55>"
$PN"F27"85;
"DDR1_DQ<56>"
$PN"U28"86;
"DDR1_DQ<57>"
$PN"AA28"87;
"DDR1_DQ<58>"
$PN"V25"88;
"DDR1_DQ<59>"
$PN"Y25"89;
"DDR1_DQ<60>"
$PN"V29"90;
"DDR1_DQ<61>"
$PN"Y29"91;
"DDR1_DQ<62>"
$PN"U26"92;
"DDR1_DQ<63>"
$PN"AA26"93;
"DDR1_CS_N<0>"
$PN"K51"101;
"DDR1_CS_N<1>"
$PN"R50"102;
"DDR1_CS_N<2>"
$PN"N46"103;
"DDR1_CS_N<3>"
$PN"V47"104;
"DDR1_CS_N<4>"
$PN"J50"105;
"DDR1_CS_N<5>"
$PN"T49"106;
"DDR1_CS_N<6>"
$PN"M45"107;
"DDR1_CS_N<7>"
$PN"R46"108;
"DDR1_CLK_DP<0>"
$PN"N54"33;
"DDR1_CLK_DP<1>"
$PN"T55"34;
"DDR1_CLK_DP<2>"
$PN"M57"35;
"DDR1_CLK_DP<3>"
$PN"T57"36;
"DDR1_CLK_DN<0>"
$PN"M53"37;
"DDR1_CLK_DN<1>"
$PN"R54"38;
"DDR1_CLK_DN<2>"
$PN"N56"39;
"DDR1_CLK_DN<3>"
$PN"R56"40;
"DDR1_CKE<0>"
$PN"N62"109;
"DDR1_CKE<1>"
$PN"R64"110;
"DDR1_CKE<2>"
$PN"K63"111;
"DDR1_CKE<3>"
$PN"L64"112;
"DDR1_CID<2>"
$PN"M47"13;
"DDR1_BG<0>"
$PN"M61"113;
"DDR1_BG<1>"
$PN"N60"114;
"DDR1_BA<0>"
$PN"T53"115;
"DDR1_BA<1>"
$PN"K55"116;
"DDR1_ALERT_N"
$PN"W62"118;
"DDR1_ACT_N"
$PN"T63"119;
%"TAP"
"6","(-5600,1325)","0","mstr_standard","I18";
;
HDL_TAP"TRUE"
BODY_TYPE"PLUMBING"
CDS_LIB"mstr_standard";
"B \NAC \NWC"12;
"S \NAC"
BN"5"19;
%"TAP"
"6","(-5600,1375)","0","mstr_standard","I19";
;
HDL_TAP"TRUE"
BODY_TYPE"PLUMBING"
CDS_LIB"mstr_standard";
"B \NAC \NWC"12;
"S \NAC"
BN"6"20;
%"TAP"
"6","(-5600,1425)","0","mstr_standard","I20";
;
HDL_TAP"TRUE"
BODY_TYPE"PLUMBING"
CDS_LIB"mstr_standard";
"B \NAC \NWC"12;
"S \NAC"
BN"7"21;
%"TAP"
"6","(-5600,1525)","0","mstr_standard","I21";
;
HDL_TAP"TRUE"
BODY_TYPE"PLUMBING"
CDS_LIB"mstr_standard";
"B \NAC \NWC"9;
"S \NAC"
BN"0"22;
%"TAP"
"6","(-5600,1575)","0","mstr_standard","I22";
;
HDL_TAP"TRUE"
BODY_TYPE"PLUMBING"
CDS_LIB"mstr_standard";
"B \NAC \NWC"9;
"S \NAC"
BN"1"23;
%"TAP"
"6","(-5600,1625)","0","mstr_standard","I23";
;
HDL_TAP"TRUE"
BODY_TYPE"PLUMBING"
CDS_LIB"mstr_standard";
"B \NAC \NWC"9;
"S \NAC"
BN"2"24;
%"TAP"
"6","(-5600,1675)","0","mstr_standard","I24";
;
HDL_TAP"TRUE"
BODY_TYPE"PLUMBING"
CDS_LIB"mstr_standard";
"B \NAC \NWC"9;
"S \NAC"
BN"3"25;
%"TAP"
"6","(-5600,1725)","0","mstr_standard","I25";
;
HDL_TAP"TRUE"
BODY_TYPE"PLUMBING"
CDS_LIB"mstr_standard";
"B \NAC \NWC"9;
"S \NAC"
BN"4"26;
%"TAP"
"6","(-5600,1775)","0","mstr_standard","I26";
;
HDL_TAP"TRUE"
BODY_TYPE"PLUMBING"
CDS_LIB"mstr_standard";
"B \NAC \NWC"9;
"S \NAC"
BN"5"27;
%"TAP"
"6","(-5600,1825)","0","mstr_standard","I27";
;
HDL_TAP"TRUE"
BODY_TYPE"PLUMBING"
CDS_LIB"mstr_standard";
"B \NAC \NWC"9;
"S \NAC"
BN"6"28;
%"TAP"
"6","(-5600,1925)","0","mstr_standard","I28";
;
HDL_TAP"TRUE"
BODY_TYPE"PLUMBING"
CDS_LIB"mstr_standard";
"B \NAC \NWC"9;
"S \NAC"
BN"8"30;
%"TAP"
"6","(-5600,1875)","0","mstr_standard","I29";
;
HDL_TAP"TRUE"
BODY_TYPE"PLUMBING"
CDS_LIB"mstr_standard";
"B \NAC \NWC"9;
"S \NAC"
BN"7"29;
%"TAP"
"6","(-5600,1975)","0","mstr_standard","I31";
;
HDL_TAP"TRUE"
BODY_TYPE"PLUMBING"
CDS_LIB"mstr_standard";
"B \NAC \NWC"9;
"S \NAC"
BN"9"31;
%"TAP"
"6","(-5600,2025)","0","mstr_standard","I32";
;
HDL_TAP"TRUE"
BODY_TYPE"PLUMBING"
CDS_LIB"mstr_standard";
"B \NAC \NWC"9;
"S \NAC"
BN"10"32;
%"TAP"
"6","(-5600,2075)","0","mstr_standard","I33";
;
HDL_TAP"TRUE"
BODY_TYPE"PLUMBING"
CDS_LIB"mstr_standard";
"B \NAC \NWC"9;
"S \NAC"
BN"11"41;
%"TAP"
"6","(-5600,2125)","0","mstr_standard","I34";
;
HDL_TAP"TRUE"
BODY_TYPE"PLUMBING"
CDS_LIB"mstr_standard";
"B \NAC \NWC"9;
"S \NAC"
BN"12"42;
%"TAP"
"6","(-5600,2175)","0","mstr_standard","I35";
;
HDL_TAP"TRUE"
BODY_TYPE"PLUMBING"
CDS_LIB"mstr_standard";
"B \NAC \NWC"9;
"S \NAC"
BN"13"43;
%"TAP"
"6","(-5600,2225)","0","mstr_standard","I36";
;
HDL_TAP"TRUE"
BODY_TYPE"PLUMBING"
CDS_LIB"mstr_standard";
"B \NAC \NWC"9;
"S \NAC"
BN"14"44;
%"TAP"
"6","(-5600,2275)","0","mstr_standard","I37";
;
HDL_TAP"TRUE"
BODY_TYPE"PLUMBING"
CDS_LIB"mstr_standard";
"B \NAC \NWC"9;
"S \NAC"
BN"15"45;
%"TAP"
"6","(-5600,2325)","0","mstr_standard","I38";
;
HDL_TAP"TRUE"
BODY_TYPE"PLUMBING"
CDS_LIB"mstr_standard";
"B \NAC \NWC"9;
"S \NAC"
BN"16"46;
%"TAP"
"6","(-5600,2375)","0","mstr_standard","I39";
;
HDL_TAP"TRUE"
BODY_TYPE"PLUMBING"
CDS_LIB"mstr_standard";
"B \NAC \NWC"9;
"S \NAC"
BN"17"47;
%"TAP"
"6","(-5600,2425)","0","mstr_standard","I40";
;
HDL_TAP"TRUE"
BODY_TYPE"PLUMBING"
CDS_LIB"mstr_standard";
"B \NAC \NWC"9;
"S \NAC"
BN"18"48;
%"TAP"
"6","(-5600,2475)","0","mstr_standard","I41";
;
HDL_TAP"TRUE"
BODY_TYPE"PLUMBING"
CDS_LIB"mstr_standard";
"B \NAC \NWC"9;
"S \NAC"
BN"19"49;
%"TAP"
"6","(-5600,2525)","0","mstr_standard","I42";
;
HDL_TAP"TRUE"
BODY_TYPE"PLUMBING"
CDS_LIB"mstr_standard";
"B \NAC \NWC"9;
"S \NAC"
BN"20"50;
%"TAP"
"6","(-5600,2575)","0","mstr_standard","I43";
;
HDL_TAP"TRUE"
BODY_TYPE"PLUMBING"
CDS_LIB"mstr_standard";
"B \NAC \NWC"9;
"S \NAC"
BN"21"51;
%"TAP"
"6","(-5600,2625)","0","mstr_standard","I44";
;
HDL_TAP"TRUE"
BODY_TYPE"PLUMBING"
CDS_LIB"mstr_standard";
"B \NAC \NWC"9;
"S \NAC"
BN"22"52;
%"TAP"
"6","(-5600,2675)","0","mstr_standard","I45";
;
HDL_TAP"TRUE"
BODY_TYPE"PLUMBING"
CDS_LIB"mstr_standard";
"B \NAC \NWC"9;
"S \NAC"
BN"23"53;
%"TAP"
"6","(-5600,2725)","0","mstr_standard","I46";
;
HDL_TAP"TRUE"
BODY_TYPE"PLUMBING"
CDS_LIB"mstr_standard";
"B \NAC \NWC"9;
"S \NAC"
BN"24"54;
%"TAP"
"6","(-5600,2825)","0","mstr_standard","I47";
;
HDL_TAP"TRUE"
BODY_TYPE"PLUMBING"
CDS_LIB"mstr_standard";
"B \NAC \NWC"9;
"S \NAC"
BN"26"56;
%"TAP"
"6","(-5600,2775)","0","mstr_standard","I48";
;
HDL_TAP"TRUE"
BODY_TYPE"PLUMBING"
CDS_LIB"mstr_standard";
"B \NAC \NWC"9;
"S \NAC"
BN"25"55;
%"TAP"
"6","(-5600,2875)","0","mstr_standard","I49";
;
HDL_TAP"TRUE"
BODY_TYPE"PLUMBING"
CDS_LIB"mstr_standard";
"B \NAC \NWC"9;
"S \NAC"
BN"27"57;
%"TAP"
"6","(-5600,625)","0","mstr_standard","I5";
;
HDL_TAP"TRUE"
BODY_TYPE"PLUMBING"
CDS_LIB"mstr_standard";
"B \NAC \NWC"10;
"S \NAC"
BN"0"37;
%"TAP"
"6","(-5600,2925)","0","mstr_standard","I50";
;
HDL_TAP"TRUE"
BODY_TYPE"PLUMBING"
CDS_LIB"mstr_standard";
"B \NAC \NWC"9;
"S \NAC"
BN"28"58;
%"TAP"
"6","(-5600,2975)","0","mstr_standard","I51";
;
HDL_TAP"TRUE"
BODY_TYPE"PLUMBING"
CDS_LIB"mstr_standard";
"B \NAC \NWC"9;
"S \NAC"
BN"29"59;
%"TAP"
"6","(-5600,3075)","0","mstr_standard","I52";
;
HDL_TAP"TRUE"
BODY_TYPE"PLUMBING"
CDS_LIB"mstr_standard";
"B \NAC \NWC"9;
"S \NAC"
BN"31"61;
%"TAP"
"6","(-5600,3025)","0","mstr_standard","I53";
;
HDL_TAP"TRUE"
BODY_TYPE"PLUMBING"
CDS_LIB"mstr_standard";
"B \NAC \NWC"9;
"S \NAC"
BN"30"60;
%"TAP"
"6","(-5600,3125)","0","mstr_standard","I54";
;
HDL_TAP"TRUE"
BODY_TYPE"PLUMBING"
CDS_LIB"mstr_standard";
"B \NAC \NWC"9;
"S \NAC"
BN"32"62;
%"TAP"
"6","(-5600,3175)","0","mstr_standard","I55";
;
HDL_TAP"TRUE"
BODY_TYPE"PLUMBING"
CDS_LIB"mstr_standard";
"B \NAC \NWC"9;
"S \NAC"
BN"33"63;
%"TAP"
"6","(-5600,3225)","0","mstr_standard","I56";
;
HDL_TAP"TRUE"
BODY_TYPE"PLUMBING"
CDS_LIB"mstr_standard";
"B \NAC \NWC"9;
"S \NAC"
BN"34"64;
%"TAP"
"6","(-5600,3325)","0","mstr_standard","I57";
;
HDL_TAP"TRUE"
BODY_TYPE"PLUMBING"
CDS_LIB"mstr_standard";
"B \NAC \NWC"9;
"S \NAC"
BN"36"66;
%"TAP"
"6","(-5600,3275)","0","mstr_standard","I58";
;
HDL_TAP"TRUE"
BODY_TYPE"PLUMBING"
CDS_LIB"mstr_standard";
"B \NAC \NWC"9;
"S \NAC"
BN"35"65;
%"TAP"
"6","(-5600,3375)","0","mstr_standard","I59";
;
HDL_TAP"TRUE"
BODY_TYPE"PLUMBING"
CDS_LIB"mstr_standard";
"B \NAC \NWC"9;
"S \NAC"
BN"37"67;
%"TAP"
"6","(-5600,675)","0","mstr_standard","I6";
;
HDL_TAP"TRUE"
BODY_TYPE"PLUMBING"
CDS_LIB"mstr_standard";
"B \NAC \NWC"10;
"S \NAC"
BN"1"38;
%"TAP"
"6","(-5600,3425)","0","mstr_standard","I60";
;
HDL_TAP"TRUE"
BODY_TYPE"PLUMBING"
CDS_LIB"mstr_standard";
"B \NAC \NWC"9;
"S \NAC"
BN"38"68;
%"TAP"
"6","(-5600,3475)","0","mstr_standard","I61";
;
HDL_TAP"TRUE"
BODY_TYPE"PLUMBING"
CDS_LIB"mstr_standard";
"B \NAC \NWC"9;
"S \NAC"
BN"39"69;
%"TAP"
"6","(-5600,3525)","0","mstr_standard","I62";
;
HDL_TAP"TRUE"
BODY_TYPE"PLUMBING"
CDS_LIB"mstr_standard";
"B \NAC \NWC"9;
"S \NAC"
BN"40"70;
%"TAP"
"6","(-5600,3575)","0","mstr_standard","I63";
;
HDL_TAP"TRUE"
BODY_TYPE"PLUMBING"
CDS_LIB"mstr_standard";
"B \NAC \NWC"9;
"S \NAC"
BN"41"71;
%"TAP"
"6","(-5600,3625)","0","mstr_standard","I64";
;
HDL_TAP"TRUE"
BODY_TYPE"PLUMBING"
CDS_LIB"mstr_standard";
"B \NAC \NWC"9;
"S \NAC"
BN"42"72;
%"TAP"
"6","(-5600,3675)","0","mstr_standard","I65";
;
HDL_TAP"TRUE"
BODY_TYPE"PLUMBING"
CDS_LIB"mstr_standard";
"B \NAC \NWC"9;
"S \NAC"
BN"43"73;
%"TAP"
"6","(-5600,3725)","0","mstr_standard","I66";
;
HDL_TAP"TRUE"
BODY_TYPE"PLUMBING"
CDS_LIB"mstr_standard";
"B \NAC \NWC"9;
"S \NAC"
BN"44"74;
%"TAP"
"6","(-5600,3775)","0","mstr_standard","I67";
;
HDL_TAP"TRUE"
BODY_TYPE"PLUMBING"
CDS_LIB"mstr_standard";
"B \NAC \NWC"9;
"S \NAC"
BN"45"75;
%"TAP"
"6","(-5600,3825)","0","mstr_standard","I68";
;
HDL_TAP"TRUE"
BODY_TYPE"PLUMBING"
CDS_LIB"mstr_standard";
"B \NAC \NWC"9;
"S \NAC"
BN"46"76;
%"TAP"
"6","(-5600,3875)","0","mstr_standard","I69";
;
HDL_TAP"TRUE"
BODY_TYPE"PLUMBING"
CDS_LIB"mstr_standard";
"B \NAC \NWC"9;
"S \NAC"
BN"47"77;
%"TAP"
"6","(-5600,775)","0","mstr_standard","I7";
;
HDL_TAP"TRUE"
BODY_TYPE"PLUMBING"
CDS_LIB"mstr_standard";
"B \NAC \NWC"10;
"S \NAC"
BN"3"40;
%"TAP"
"6","(-5600,3925)","0","mstr_standard","I70";
;
HDL_TAP"TRUE"
BODY_TYPE"PLUMBING"
CDS_LIB"mstr_standard";
"B \NAC \NWC"9;
"S \NAC"
BN"48"78;
%"TAP"
"6","(-5600,3975)","0","mstr_standard","I71";
;
HDL_TAP"TRUE"
BODY_TYPE"PLUMBING"
CDS_LIB"mstr_standard";
"B \NAC \NWC"9;
"S \NAC"
BN"49"79;
%"TAP"
"6","(-5600,4025)","0","mstr_standard","I73";
;
HDL_TAP"TRUE"
BODY_TYPE"PLUMBING"
CDS_LIB"mstr_standard";
"B \NAC \NWC"9;
"S \NAC"
BN"50"80;
%"TAP"
"6","(-5600,4075)","0","mstr_standard","I74";
;
HDL_TAP"TRUE"
BODY_TYPE"PLUMBING"
CDS_LIB"mstr_standard";
"B \NAC \NWC"9;
"S \NAC"
BN"51"81;
%"TAP"
"6","(-5600,4125)","0","mstr_standard","I75";
;
HDL_TAP"TRUE"
BODY_TYPE"PLUMBING"
CDS_LIB"mstr_standard";
"B \NAC \NWC"9;
"S \NAC"
BN"52"82;
%"TAP"
"6","(-5600,4175)","0","mstr_standard","I76";
;
HDL_TAP"TRUE"
BODY_TYPE"PLUMBING"
CDS_LIB"mstr_standard";
"B \NAC \NWC"9;
"S \NAC"
BN"53"83;
%"TAP"
"6","(-5600,4225)","0","mstr_standard","I77";
;
HDL_TAP"TRUE"
BODY_TYPE"PLUMBING"
CDS_LIB"mstr_standard";
"B \NAC \NWC"9;
"S \NAC"
BN"54"84;
%"TAP"
"6","(-5600,4275)","0","mstr_standard","I78";
;
HDL_TAP"TRUE"
BODY_TYPE"PLUMBING"
CDS_LIB"mstr_standard";
"B \NAC \NWC"9;
"S \NAC"
BN"55"85;
%"TAP"
"6","(-5600,4325)","0","mstr_standard","I79";
;
HDL_TAP"TRUE"
BODY_TYPE"PLUMBING"
CDS_LIB"mstr_standard";
"B \NAC \NWC"9;
"S \NAC"
BN"56"86;
%"TAP"
"6","(-5600,725)","0","mstr_standard","I8";
;
HDL_TAP"TRUE"
BODY_TYPE"PLUMBING"
CDS_LIB"mstr_standard";
"B \NAC \NWC"10;
"S \NAC"
BN"2"39;
%"TAP"
"6","(-5600,4375)","0","mstr_standard","I80";
;
HDL_TAP"TRUE"
BODY_TYPE"PLUMBING"
CDS_LIB"mstr_standard";
"B \NAC \NWC"9;
"S \NAC"
BN"57"87;
%"TAP"
"6","(-5600,4425)","0","mstr_standard","I81";
;
HDL_TAP"TRUE"
BODY_TYPE"PLUMBING"
CDS_LIB"mstr_standard";
"B \NAC \NWC"9;
"S \NAC"
BN"58"88;
%"TAP"
"6","(-5600,4475)","0","mstr_standard","I82";
;
HDL_TAP"TRUE"
BODY_TYPE"PLUMBING"
CDS_LIB"mstr_standard";
"B \NAC \NWC"9;
"S \NAC"
BN"59"89;
%"TAP"
"6","(-5600,4525)","0","mstr_standard","I83";
;
HDL_TAP"TRUE"
BODY_TYPE"PLUMBING"
CDS_LIB"mstr_standard";
"B \NAC \NWC"9;
"S \NAC"
BN"60"90;
%"TAP"
"6","(-5600,4575)","0","mstr_standard","I84";
;
HDL_TAP"TRUE"
BODY_TYPE"PLUMBING"
CDS_LIB"mstr_standard";
"B \NAC \NWC"9;
"S \NAC"
BN"61"91;
%"TAP"
"6","(-5600,4625)","0","mstr_standard","I85";
;
HDL_TAP"TRUE"
BODY_TYPE"PLUMBING"
CDS_LIB"mstr_standard";
"B \NAC \NWC"9;
"S \NAC"
BN"62"92;
%"TAP"
"6","(-5600,4675)","0","mstr_standard","I86";
;
HDL_TAP"TRUE"
BODY_TYPE"PLUMBING"
CDS_LIB"mstr_standard";
"B \NAC \NWC"9;
"S \NAC"
BN"63"93;
%"TAP"
"6","(-2875,775)","2","mstr_standard","I87";
;
HDL_TAP"TRUE"
BODY_TYPE"PLUMBING"
CDS_LIB"mstr_standard";
"B \NAC \NWC"4;
"S \NAC"
BN"1"116;
%"TAP"
"6","(-2875,725)","2","mstr_standard","I88";
;
HDL_TAP"TRUE"
BODY_TYPE"PLUMBING"
CDS_LIB"mstr_standard";
"B \NAC \NWC"4;
"S \NAC"
BN"0"115;
%"TAP"
"6","(-2875,825)","2","mstr_standard","I89";
;
HDL_TAP"TRUE"
BODY_TYPE"PLUMBING"
CDS_LIB"mstr_standard";
"B \NAC \NWC"5;
"S \NAC"
BN"0"113;
%"TAP"
"6","(-5600,875)","0","mstr_standard","I9";
;
HDL_TAP"TRUE"
BODY_TYPE"PLUMBING"
CDS_LIB"mstr_standard";
"B \NAC \NWC"11;
"S \NAC"
BN"1"34;
%"TAP"
"6","(-2875,875)","2","mstr_standard","I90";
;
HDL_TAP"TRUE"
BODY_TYPE"PLUMBING"
CDS_LIB"mstr_standard";
"B \NAC \NWC"5;
"S \NAC"
BN"1"114;
%"TAP"
"6","(-2875,1075)","2","mstr_standard","I91";
;
HDL_TAP"TRUE"
BODY_TYPE"PLUMBING"
CDS_LIB"mstr_standard";
"B \NAC \NWC"7;
"S \NAC"
BN"2"103;
%"TAP"
"6","(-2875,1025)","2","mstr_standard","I92";
;
HDL_TAP"TRUE"
BODY_TYPE"PLUMBING"
CDS_LIB"mstr_standard";
"B \NAC \NWC"7;
"S \NAC"
BN"1"102;
%"TAP"
"6","(-2875,975)","2","mstr_standard","I93";
;
HDL_TAP"TRUE"
BODY_TYPE"PLUMBING"
CDS_LIB"mstr_standard";
"B \NAC \NWC"7;
"S \NAC"
BN"0"101;
%"TAP"
"6","(-2875,1175)","2","mstr_standard","I94";
;
HDL_TAP"TRUE"
BODY_TYPE"PLUMBING"
CDS_LIB"mstr_standard";
"B \NAC \NWC"7;
"S \NAC"
BN"4"105;
%"TAP"
"6","(-2875,1125)","2","mstr_standard","I95";
;
HDL_TAP"TRUE"
BODY_TYPE"PLUMBING"
CDS_LIB"mstr_standard";
"B \NAC \NWC"7;
"S \NAC"
BN"3"104;
%"TAP"
"6","(-2875,1225)","2","mstr_standard","I96";
;
HDL_TAP"TRUE"
BODY_TYPE"PLUMBING"
CDS_LIB"mstr_standard";
"B \NAC \NWC"7;
"S \NAC"
BN"5"106;
%"TAP"
"6","(-2875,1275)","2","mstr_standard","I97";
;
HDL_TAP"TRUE"
BODY_TYPE"PLUMBING"
CDS_LIB"mstr_standard";
"B \NAC \NWC"7;
"S \NAC"
BN"6"107;
%"TAP"
"6","(-2875,1325)","2","mstr_standard","I98";
;
HDL_TAP"TRUE"
BODY_TYPE"PLUMBING"
CDS_LIB"mstr_standard";
"B \NAC \NWC"7;
"S \NAC"
BN"7"108;
%"TAP"
"6","(-2875,1425)","2","mstr_standard","I99";
;
HDL_TAP"TRUE"
BODY_TYPE"PLUMBING"
CDS_LIB"mstr_standard";
"B \NAC \NWC"8;
"S \NAC"
BN"0"94;
END.
